# SCM (Grand Teton) — schematic netlist excerpt (pin names and nets, part order shuffled) for the footprints in the layout excerpt that follows; sources: Cadence DE-HDL packaged netlist, KiCad conversion of 12092022_DA0F0TMDCD0_F0T_Management_Board_D_brd_V3_OCP.brd

DB3  TDR_3P  EMPTY  pkg TH2  page 60
  GND  = T_GND
  IO1  = TDR_SE_50_OHM_IN2
  IO2  = TDR_SE_50_OHM_IN2

R281  Q_RES  0 5% CHIP  pkg 0402LF  page 17 : A = P1V0_AUX ; B = P1V2_P1V0_I3C_VDDL2
R806  Q_RES  4.7K 1% CHIP  pkg 0402LF  page 34 : A = P3V3_AUX ; B = PU_25M_FPGA_CLK_EN

(kicad_pcb
	(version 20260206)
	(generator "pcbnew")
	(generator_version "10.0")
	(general
		(thickness 1.6)
		(legacy_teardrops no)
	)
	(paper "A4")
	(title_block
		(title "12092022_DA0F0TMDCD0_F0T_Management_Board_D_brd_V3_OCP.brd")
		(comment 1 "Grand Teton / footprints 1436-1438 of 1440")
	)
	(layers
		(0 "F.Cu" signal "TOP")
		(4 "In1.Cu" signal "GND")
		(6 "In2.Cu" signal "IN1")
		(8 "In3.Cu" signal "GND1")
		(10 "In4.Cu" signal "IN2")
		(12 "In5.Cu" signal "VCC")
		(14 "In6.Cu" signal "VCC1")
		(16 "In7.Cu" signal "IN3")
		(18 "In8.Cu" signal "GND2")
		(20 "In9.Cu" signal "IN4")
		(22 "In10.Cu" signal "GND3")
		(2 "B.Cu" signal "BOTTOM")
		(9 "F.Adhes" user "F.Adhesive")
		(11 "B.Adhes" user "B.Adhesive")
		(13 "F.Paste" user "Package Geometry/Pastemask Top")
		(15 "B.Paste" user "Package Geometry/Pastemask Bottom")
		(5 "F.SilkS" user "Ref Des/Silkscreen Top")
		(7 "B.SilkS" user "Ref Des/Silkscreen Bottom")
		(1 "F.Mask" user "Board Geometry/Soldermask Top")
		(3 "B.Mask" user "Board Geometry/Soldermask Bottom")
		(17 "Dwgs.User" user "User.Drawings")
		(19 "Cmts.User" user "User.Comments")
		(21 "Eco1.User" user "User.Eco1")
		(23 "Eco2.User" user "User.Eco2")
		(25 "Edge.Cuts" user "Board Geometry/Outline")
		(27 "Margin" user)
		(31 "F.CrtYd" user "Package Geometry/Place Bound Top")
		(29 "B.CrtYd" user "Package Geometry/Place Bound Bottom")
		(35 "F.Fab" user "Ref Des/Assembly Top")
		(33 "B.Fab" user "Ref Des/Assembly Bottom")
	)
	(footprint ""
		(layer "B.Cu")
		(at -14.2494 -66.929 180)
		(property "Reference" "DB3"
			(at 2.71526 -6.12521 0)
			(unlocked yes)
			(layer "B.SilkS")
			(effects
				(font
					(size 0.7874 0.5842)
					(thickness 0.1524)
				)
				(justify left mirror)
			)
		)
		(property "Value" ""
			(at 0 0 0)
			(layer "B.Fab")
			(effects
				(font
					(size 1.27 1.27)
				)
				(justify mirror)
			)
		)
		(duplicate_pad_numbers_are_jumpers no)
		(fp_line
			(start 3.330702 -4.771136)
			(end -3.330702 -4.771136)
			(stroke
				(width 0.1524)
				(type default)
			)
			(layer "B.SilkS")
		)
		(fp_line
			(start 0 4.011168)
			(end 3.330702 -4.771136)
			(stroke
				(width 0.1524)
				(type default)
			)
			(layer "B.SilkS")
		)
		(fp_line
			(start -3.330702 -4.771136)
			(end 0 4.011168)
			(stroke
				(width 0.1524)
				(type default)
			)
			(layer "B.SilkS")
		)
		(fp_line
			(start 3.330702 -4.771136)
			(end -3.330702 -4.771136)
			(stroke
				(width 0.1)
				(type default)
			)
			(layer "B.Fab")
		)
		(fp_line
			(start 0 4.011168)
			(end 3.330702 -4.771136)
			(stroke
				(width 0.1)
				(type default)
			)
			(layer "B.Fab")
		)
		(fp_line
			(start -3.330702 -4.771136)
			(end 0 4.011168)
			(stroke
				(width 0.1)
				(type default)
			)
			(layer "B.Fab")
		)
		(pad "1" thru_hole circle
			(at 0 0)
			(size 2.159 2.159)
			(drill 1.7018)
			(layers "*.Cu" "*.Mask")
			(remove_unused_layers no)
			(net "T_GND")
			(clearance 0.0254)
			(thermal_gap 0.0254)
		)
		(pad "2" thru_hole circle
			(at 1.27 -3.348736)
			(size 2.159 2.159)
			(drill 1.7018)
			(layers "*.Cu" "*.Mask")
			(remove_unused_layers no)
			(net "TDR_SE_50_OHM_IN2")
			(clearance 0.0254)
			(thermal_gap 0.0254)
		)
		(pad "3" thru_hole circle
			(at -1.27 -3.348736)
			(size 2.159 2.159)
			(drill 1.7018)
			(layers "*.Cu" "*.Mask")
			(remove_unused_layers no)
			(net "TDR_SE_50_OHM_IN2")
			(clearance 0.0254)
			(thermal_gap 0.0254)
		)
	)
	(footprint ""
		(layer "B.Cu")
		(at 41.143936 -52.40147 180)
		(property "Reference" "R281"
			(at 0 0 0)
			(layer "B.SilkS")
			(hide yes)
			(effects
				(font
					(size 1.27 1.27)
				)
				(justify mirror)
			)
		)
		(property "Value" ""
			(at 0 0 0)
			(layer "B.Fab")
			(effects
				(font
					(size 1.27 1.27)
				)
				(justify mirror)
			)
		)
		(duplicate_pad_numbers_are_jumpers no)
		(fp_line
			(start 0.7874 0.4064)
			(end 0.7874 -0.4064)
			(stroke
				(width 0.1524)
				(type default)
			)
			(layer "B.SilkS")
		)
		(fp_line
			(start 0.7874 -0.4064)
			(end -0.7874 -0.4064)
			(stroke
				(width 0.1524)
				(type default)
			)
			(layer "B.SilkS")
		)
		(fp_line
			(start -0.7874 0.4064)
			(end 0.7874 0.4064)
			(stroke
				(width 0.1524)
				(type default)
			)
			(layer "B.SilkS")
		)
		(fp_line
			(start -0.7874 -0.4064)
			(end -0.7874 0.4064)
			(stroke
				(width 0.1524)
				(type default)
			)
			(layer "B.SilkS")
		)
		(fp_line
			(start 0.67945 0.3048)
			(end 0.67945 -0.305054)
			(stroke
				(width 0.1)
				(type default)
			)
			(layer "B.Fab")
		)
		(fp_line
			(start 0.67945 -0.305054)
			(end 0.12065 -0.305054)
			(stroke
				(width 0.1)
				(type default)
			)
			(layer "B.Fab")
		)
		(fp_line
			(start 0.12065 0.3048)
			(end 0.67945 0.3048)
			(stroke
				(width 0.1)
				(type default)
			)
			(layer "B.Fab")
		)
		(fp_line
			(start 0.12065 0.2794)
			(end 0.12065 0.3048)
			(stroke
				(width 0.1)
				(type default)
			)
			(layer "B.Fab")
		)
		(fp_line
			(start 0.12065 -0.2794)
			(end -0.12065 -0.2794)
			(stroke
				(width 0.1)
				(type default)
			)
			(layer "B.Fab")
		)
		(fp_line
			(start 0.12065 -0.305054)
			(end 0.12065 -0.2794)
			(stroke
				(width 0.1)
				(type default)
			)
			(layer "B.Fab")
		)
		(fp_line
			(start -0.120396 0.3048)
			(end -0.120396 0.2794)
			(stroke
				(width 0.1)
				(type default)
			)
			(layer "B.Fab")
		)
		(fp_line
			(start -0.120396 0.2794)
			(end 0.12065 0.2794)
			(stroke
				(width 0.1)
				(type default)
			)
			(layer "B.Fab")
		)
		(fp_line
			(start -0.12065 -0.2794)
			(end -0.12065 -0.3048)
			(stroke
				(width 0.1)
				(type default)
			)
			(layer "B.Fab")
		)
		(fp_line
			(start -0.12065 -0.3048)
			(end -0.67945 -0.3048)
			(stroke
				(width 0.1)
				(type default)
			)
			(layer "B.Fab")
		)
		(fp_line
			(start -0.67945 0.3048)
			(end -0.120396 0.3048)
			(stroke
				(width 0.1)
				(type default)
			)
			(layer "B.Fab")
		)
		(fp_line
			(start -0.67945 -0.3048)
			(end -0.67945 0.3048)
			(stroke
				(width 0.1)
				(type default)
			)
			(layer "B.Fab")
		)
		(pad "1" smd circle
			(at 0.40005 0)
			(size 0 0)
			(layers "B.Cu" "B.Mask" "B.Paste")
			(net "P1V0_AUX")
		)
		(pad "2" smd circle
			(at -0.40005 0)
			(size 0 0)
			(layers "B.Cu" "B.Mask" "B.Paste")
			(net "P1V2_P1V0_I3C_VDDL2")
		)
	)
	(footprint ""
		(layer "B.Cu")
		(at 18.2626 -78.359 -90)
		(property "Reference" "R806"
			(at 0 0 90)
			(layer "B.SilkS")
			(hide yes)
			(effects
				(font
					(size 1.27 1.27)
				)
				(justify mirror)
			)
		)
		(property "Value" ""
			(at 0 0 90)
			(layer "B.Fab")
			(effects
				(font
					(size 1.27 1.27)
				)
				(justify mirror)
			)
		)
		(duplicate_pad_numbers_are_jumpers no)
		(fp_line
			(start -0.7874 0.4064)
			(end 0.7874 0.4064)
			(stroke
				(width 0.1524)
				(type default)
			)
			(layer "B.SilkS")
		)
		(fp_line
			(start 0.7874 0.4064)
			(end 0.7874 -0.4064)
			(stroke
				(width 0.1524)
				(type default)
			)
			(layer "B.SilkS")
		)
		(fp_line
			(start -0.7874 -0.4064)
			(end -0.7874 0.4064)
			(stroke
				(width 0.1524)
				(type default)
			)
			(layer "B.SilkS")
		)
		(fp_line
			(start 0.7874 -0.4064)
			(end -0.7874 -0.4064)
			(stroke
				(width 0.1524)
				(type default)
			)
			(layer "B.SilkS")
		)
		(fp_line
			(start -0.67945 0.3048)
			(end -0.120396 0.3048)
			(stroke
				(width 0.1)
				(type default)
			)
			(layer "B.Fab")
		)
		(fp_line
			(start -0.120396 0.3048)
			(end -0.120396 0.2794)
			(stroke
				(width 0.1)
				(type default)
			)
			(layer "B.Fab")
		)
		(fp_line
			(start 0.12065 0.3048)
			(end 0.67945 0.3048)
			(stroke
				(width 0.1)
				(type default)
			)
			(layer "B.Fab")
		)
		(fp_line
			(start 0.67945 0.3048)
			(end 0.67945 -0.305054)
			(stroke
				(width 0.1)
				(type default)
			)
			(layer "B.Fab")
		)
		(fp_line
			(start -0.120396 0.2794)
			(end 0.12065 0.2794)
			(stroke
				(width 0.1)
				(type default)
			)
			(layer "B.Fab")
		)
		(fp_line
			(start 0.12065 0.2794)
			(end 0.12065 0.3048)
			(stroke
				(width 0.1)
				(type default)
			)
			(layer "B.Fab")
		)
		(fp_line
			(start -0.12065 -0.2794)
			(end -0.12065 -0.3048)
			(stroke
				(width 0.1)
				(type default)
			)
			(layer "B.Fab")
		)
		(fp_line
			(start 0.12065 -0.2794)
			(end -0.12065 -0.2794)
			(stroke
				(width 0.1)
				(type default)
			)
			(layer "B.Fab")
		)
		(fp_line
			(start -0.67945 -0.3048)
			(end -0.67945 0.3048)
			(stroke
				(width 0.1)
				(type default)
			)
			(layer "B.Fab")
		)
		(fp_line
			(start -0.12065 -0.3048)
			(end -0.67945 -0.3048)
			(stroke
				(width 0.1)
				(type default)
			)
			(layer "B.Fab")
		)
		(fp_line
			(start 0.12065 -0.305054)
			(end 0.12065 -0.2794)
			(stroke
				(width 0.1)
				(type default)
			)
			(layer "B.Fab")
		)
		(fp_line
			(start 0.67945 -0.305054)
			(end 0.12065 -0.305054)
			(stroke
				(width 0.1)
				(type default)
			)
			(layer "B.Fab")
		)
		(pad "1" smd circle
			(at 0.40005 0 90)
			(size 0 0)
			(layers "B.Cu" "B.Mask" "B.Paste")
			(net "P3V3_AUX")
		)
		(pad "2" smd circle
			(at -0.40005 0 90)
			(size 0 0)
			(layers "B.Cu" "B.Mask" "B.Paste")
			(net "PU_25M_FPGA_CLK_EN")
		)
	)
)
